FILE_TYPE = CONNECTIVITY;
{Allegro Design Entry HDL 17.2-2016 S081 (4005846) 1/11/2022}
"PAGE_NUMBER" = 176;
0"NC";
1"P3V3_AUX\g";
2"P3V3_AUX\g";
3"GND\g";
4"GND\g";
5"GND\g";
6"FM_PCH_BMC_RST_R_N"CDS_PHYS_NET_NAME"TP_PCH_GPP_L_8";
7"PD_GPP_I_13"CDS_PHYS_NET_NAME"OCP_SFF_BIF1_N";
8"PD_GPP_I_17"CDS_PHYS_NET_NAME"OCP_LFF_4CP_BIF0_N";
9"PD_GPP_M_15"CDS_PHYS_NET_NAME"FM_PCIE_EDSFF4A_PRSNT_1_N";
10"PD_GPP_M_16"CDS_PHYS_NET_NAME"RISER2_TYPE_ID1";
11"PD_GPP_M_17"CDS_PHYS_NET_NAME"RISER2_TYPE_ID1";
12"FAB_REV_ID0"CDS_PHYS_NET_NAME"RISER2_TYPE_ID";
13"FAB_REV_ID1"CDS_PHYS_NET_NAME"PCIE_RISER2_PRSNT2_N";
14"FAB_REV_ID2"CDS_PHYS_NET_NAME"RISER2_TYPE_ID";
15"FM_BOARD_SKU_ID1"CDS_PHYS_NET_NAME"RISER3_TYPE_ID";
16"FM_BOARD_SKU_ID2"CDS_PHYS_NET_NAME"RISER2_TYPE_ID1";
17"FM_BOARD_SKU_ID3"CDS_PHYS_NET_NAME"TP_GPP_M_8";
18"PD_GPP_M_8"CDS_PHYS_NET_NAME"FM_PCIE_EDSFF4A_PRSNT_1_N";
19"FM_PCH_BIOS_RCVR_MODE"CDS_PHYS_NET_NAME"H_CPU0_PMSYNC_PCH_R";
20"TP_GPP_M_12"CDS_PHYS_NET_NAME"FM_PCIE_EDSFF4A_PRSNT_1_N";
21"FM_PCH_BMC_RST_R_N"CDS_PHYS_NET_NAME"TP_PCH_GPP_L_8";
22"PD_GPP_I_13"CDS_PHYS_NET_NAME"TP_PCH_GPP_L_8";
23"PD_GPP_I_14"CDS_PHYS_NET_NAME"TP_PCH_GPP_L_8";
24"PD_GPP_I_15"CDS_PHYS_NET_NAME"TP_PCH_GPP_L_8";
25"PD_GPP_I_16"CDS_PHYS_NET_NAME"TP_PCH_GPP_L_8";
26"PD_GPP_I_17"CDS_PHYS_NET_NAME"OCP_LFF_4CP_BIF0_N";
27"IRQ_TPM_SPI_N"CDS_PHYS_NET_NAME"H_CPU0_PMSYNC_PCH_R";
28"FM_PCH_DFXTESTMODE"CDS_PHYS_NET_NAME"H_CPU0_PMSYNC_PCH_R";
29"TP_GPP_L_8"CDS_PHYS_NET_NAME"RISER2_TYPE_ID1";
30"TP_GPP_L_7"CDS_PHYS_NET_NAME"RISER2_TYPE_ID1";
31"H_CPU0_PMSYNC_PCH_R2";
32"TP_GPP_L_2"CDS_PHYS_NET_NAME"RISER2_TYPE_ID1";
33"FM_PASSWORD_CLEAR_N";
34"FM_MFG_MODE";
35"PD_PCH_GPP_E_10"CDS_PHYS_NET_NAME"FM_PCIE_EDSFF2B_PRSNT_1_N";
36"PD_PCH_GPP_E_12"CDS_PHYS_NET_NAME"FM_PCH_SLP_S4_N";
37"FM_BOARD_SKU_ID0"CDS_PHYS_NET_NAME"PCIE_RISER2_PRSNT2_N";
38"FM_BOARD_SKU_ID4"CDS_PHYS_NET_NAME"RISER2_TYPE_ID1";
39"FM_ME_RCVR_N";
40"FM_BIOS_ADV_FUNCTIONS";
41"H_CPU0_PMDOWN_PCH";
42"FM_PCH_XTALSEL"CDS_PHYS_NET_NAME"H_CPU0_PMSYNC_PCH_R";
43"PD_PCH_GPP_E_11"CDS_PHYS_NET_NAME"FM_PCIE_EDSFF4B_PRSNT_1_N";
44"PD_GPP_I_16"CDS_PHYS_NET_NAME"TP_PCH_GPP_L_8";
45"PD_GPP_M_8"CDS_PHYS_NET_NAME"FM_PCIE_EDSFF4A_PRSNT_1_N";
46"PD_PCH_GPP_E_14"CDS_PHYS_NET_NAME"FM_PCH_SLP_S4_N";
47"PD_GPP_I_15"CDS_PHYS_NET_NAME"TP_PCH_GPP_L_8";
48"PD_PCH_GPP_E_13"CDS_PHYS_NET_NAME"TP_PCH_MGPIO_TEST1";
49"PD_PCH_GPP_E_8"CDS_PHYS_NET_NAME"FM_EDSFF2_TYPE_ID";
50"PD_PCH_GPP_E_9"CDS_PHYS_NET_NAME"FM_PCIE_EDSFF1B_PRSNT_1_N";
51"PD_GPP_I_14"CDS_PHYS_NET_NAME"OCP_SFF_BIF2_N";
52"PD_PCH_GPP_E_3"CDS_PHYS_NET_NAME"TP_EDSFF1A_TYPE_ID";
53"FM_M2_E1S_E6_PEDET";
54"FM_PCH_EXTERNALCLKMODE"CDS_PHYS_NET_NAME"FM_PCH_SLP_S4_N";
55"PD_GPP_M_15"CDS_PHYS_NET_NAME"FM_PCIE_EDSFF4A_PRSNT_1_N";
56"PD_GPP_M_16"CDS_PHYS_NET_NAME"RISER2_TYPE_ID1";
57"PD_GPP_M_17"CDS_PHYS_NET_NAME"RISER2_TYPE_ID1";
58"FM_PCH_IO_EXPANDER"CDS_PHYS_NET_NAME"FM_PCH_SLP_S4_N";
59"FM_PCH_VISA_DEFAULT"CDS_PHYS_NET_NAME"FM_PCH_SLP_S4_N";
60"TP_PCH_GPP_E_1"CDS_PHYS_NET_NAME"FM_PCH_SLP_S4_N";
61"TP_PCH_GPP_E_0"CDS_PHYS_NET_NAME"FM_PCH_SLP_S4_N";
62"FM_LT_KEY_DOWNGRADE_N"CDS_PHYS_NET_NAME"FM_PCH_SLP_S4_N";
63"FM_PCH_XTAL_INPUT_MODE_MGPIO_TEST3"CDS_PHYS_NET_NAME"FM_PCH_SLP_S4_N";
64"PD_PCH_GPP_E_14"CDS_PHYS_NET_NAME"FM_PCH_SLP_S4_N";
65"PD_PCH_GPP_E_12"CDS_PHYS_NET_NAME"FM_PCH_SLP_S4_N";
66"PD_PCH_GPP_E_11"CDS_PHYS_NET_NAME"FM_PCIE_EDSFF4B_PRSNT_1_N";
67"PD_PCH_GPP_E_10"CDS_PHYS_NET_NAME"FM_PCIE_EDSFF2B_PRSNT_1_N";
68"PD_PCH_GPP_E_9"CDS_PHYS_NET_NAME"FM_PCIE_EDSFF1B_PRSNT_1_N";
69"PD_PCH_GPP_E_8"CDS_PHYS_NET_NAME"FM_EDSFF2_TYPE_ID";
70"FM_M2_SSD0_E7_PEDET"CDS_PHYS_NET_NAME"FM_PCH_SLP_S4_N";
71"PD_PCH_GPP_E_13"CDS_PHYS_NET_NAME"TP_PCH_MGPIO_TEST1";
72"FM_ME_AUTHN_FAIL"CDS_PHYS_NET_NAME"FM_PCH_SLP_S4_N";
73"TP_PCH_GPP_E_2"CDS_PHYS_NET_NAME"TP_EDSFF1A_TYPE_ID";
74"PD_PCH_GPP_E_3"CDS_PHYS_NET_NAME"TP_EDSFF1A_TYPE_ID";
75"TP_EDSFF1A_TYPE_ID"CDS_PHYS_NET_NAME"FM_PCH_SLP_S4_N";
76"TP_EDSFF1B_TYPE_ID"CDS_PHYS_NET_NAME"FM_EDSFF1_TYPE_ID";
77"FM_M2_SSD0_E7_PEDET";
78"TP_PCH_MGPIO_TEST1"CDS_PHYS_NET_NAME"FM_PCH_SLP_S4_N";
79"PU_PCH_PMCALERT_N"CDS_PHYS_NET_NAME"FM_PCH_SLP_S4_N";
80"FM_M2_E1S_E6_PEDET"CDS_PHYS_NET_NAME"FM_PCH_SLP_S4_N";
81"FM_ME_BT_DONE"CDS_PHYS_NET_NAME"FM_PCH_SLP_S4_N";
82"FM_DEBUG_PORT_PRSNT_R_N"CDS_PHYS_NET_NAME"FM_PCH_SLP_S4_N";
83"FM_TPM_PRSNT_N"CDS_PHYS_NET_NAME"FM_PCH_SLP_S4_N";
84"FM_PCH_RING_OSC_BYPASS_MGPIO_TEST2"CDS_PHYS_NET_NAME"FM_PCH_SLP_S4_N";
85"FM_PCH_MCRO_LDO"CDS_PHYS_NET_NAME"FM_PCH_SLP_S4_N";
86"FM_PS_PWROK_DLY_R_SEL"CDS_PHYS_NET_NAME"FM_PCH_SLP_S4_N";
%"UNIVERSAL_GND"
"1","(-2475,-75)","0","logical_power","I161";
;
CDS_LIB"logical_power"
HDL_POWER"GND"
ROOM"IO_SLOT";
"A"4;
%"UNIVERSAL_GND"
"1","(-2200,-75)","0","logical_power","I163";
;
CDS_LIB"logical_power"
HDL_POWER"GND"
ROOM"IO_SLOT";
"A"5;
%"UNIVERSAL_POWER"
"1","(-2475,1175)","0","logical_power","I168";
;
HDL_POWER"P3V3_AUX"
CDS_LIB"logical_power";
"A"2;
%"Q_RES"
"2","(-2475,800)","0","pure_quanta","I173";
;
PART_NUMBER"CS31002FB08"
WATTAGE"1/16W"
TOLERANCE"1%"
PACK_TYPE"0402LF"
VALUE"10K"
MATERIAL"EMPTY"
$LOCATION"R2508"
CDS_LIB"pure_quanta"
CDS_LOCATION"R2508"
$SEC"1"
CDS_SEC"1";
"A"
$PN"1"2;
"B"
$PN"2"77;
%"Q_RES"
"2","(-2475,150)","0","pure_quanta","I174";
;
PART_NUMBER"CS21002FB06"
WATTAGE"1/16W"
VALUE"1K"
PACK_TYPE"0402LF"
MATERIAL"EMPTY"
TOLERANCE"1%"
$LOCATION"R2509"
CDS_LIB"pure_quanta"
CDS_LOCATION"R2509"
$SEC"1"
CDS_SEC"1";
"A"
$PN"1"77;
"B"
$PN"2"4;
%"Q_RES"
"2","(-2200,800)","0","pure_quanta","I175";
;
PART_NUMBER"CS31002FB08"
PACK_TYPE"0402LF"
MATERIAL"EMPTY"
WATTAGE"1/16W"
VALUE"10K"
TOLERANCE"1%"
$LOCATION"R2510"
CDS_LIB"pure_quanta"
CDS_LOCATION"R2510"
$SEC"1"
CDS_SEC"1";
"A"
$PN"1"2;
"B"
$PN"2"53;
%"Q_RES"
"2","(-2200,150)","0","pure_quanta","I176";
;
PART_NUMBER"CS21002FB06"
PACK_TYPE"0402LF"
MATERIAL"EMPTY"
WATTAGE"1/16W"
TOLERANCE"1%"
VALUE"1K"
$LOCATION"R2511"
CDS_LIB"pure_quanta"
CDS_LOCATION"R2511"
$SEC"1"
CDS_SEC"1";
"A"
$PN"1"53;
"B"
$PN"2"5;
%"Q_RES"
"1","(1925,525)","0","pure_quanta","I183";
;
PART_NUMBER"CS31002FB08"
TOLERANCE"1%"
MATERIAL"CHIP"
VALUE"10K"
$LOCATION"R4105"
CDS_LIB"pure_quanta"
WATTAGE"1/16W"
PACK_TYPE"0402LF"
CDS_LOCATION"R4105"
$SEC"1"
CDS_SEC"1";
"B"
$PN"2"3;
"A"
$PN"1"9;
%"Q_RES"
"1","(1925,425)","0","pure_quanta","I184";
;
PART_NUMBER"CS31002FB08"
MATERIAL"CHIP"
TOLERANCE"1%"
VALUE"10K"
$LOCATION"R4106"
CDS_LIB"pure_quanta"
WATTAGE"1/16W"
PACK_TYPE"0402LF"
CDS_LOCATION"R4106"
$SEC"1"
CDS_SEC"1";
"B"
$PN"2"3;
"A"
$PN"1"45;
%"Q_RES"
"1","(1925,625)","0","pure_quanta","I185";
;
PART_NUMBER"CS31002FB08"
MATERIAL"CHIP"
TOLERANCE"1%"
VALUE"10K"
$LOCATION"R4104"
PACK_TYPE"0402LF"
WATTAGE"1/16W"
CDS_LIB"pure_quanta"
CDS_LOCATION"R4104"
$SEC"1"
CDS_SEC"1";
"B"
$PN"2"3;
"A"
$PN"1"10;
%"Q_RES"
"1","(1925,725)","0","pure_quanta","I186";
;
PART_NUMBER"CS31002FB08"
MATERIAL"CHIP"
VALUE"10K"
TOLERANCE"1%"
$LOCATION"R4103"
CDS_LIB"pure_quanta"
WATTAGE"1/16W"
PACK_TYPE"0402LF"
CDS_LOCATION"R4103"
$SEC"1"
CDS_SEC"1";
"B"
$PN"2"3;
"A"
$PN"1"11;
%"Q_RES"
"1","(1925,125)","0","pure_quanta","I195";
;
PART_NUMBER"CS31002FB08"
TOLERANCE"1%"
VALUE"10K"
MATERIAL"CHIP"
$LOCATION"R4109"
PACK_TYPE"0402LF"
WATTAGE"1/16W"
CDS_LIB"pure_quanta"
CDS_LOCATION"R4109"
$SEC"1"
CDS_SEC"1";
"B"
$PN"2"3;
"A"
$PN"1"47;
%"Q_RES"
"1","(1925,225)","0","pure_quanta","I196";
;
PART_NUMBER"CS31002FB08"
TOLERANCE"1%"
VALUE"10K"
MATERIAL"CHIP"
$LOCATION"R4108"
CDS_LIB"pure_quanta"
WATTAGE"1/16W"
PACK_TYPE"0402LF"
CDS_LOCATION"R4108"
$SEC"1"
CDS_SEC"1";
"B"
$PN"2"3;
"A"
$PN"1"44;
%"Q_RES"
"1","(1925,325)","0","pure_quanta","I197";
;
PART_NUMBER"CS31002FB08"
VALUE"10K"
MATERIAL"CHIP"
TOLERANCE"1%"
$LOCATION"R4107"
CDS_LIB"pure_quanta"
WATTAGE"1/16W"
PACK_TYPE"0402LF"
CDS_LOCATION"R4107"
$SEC"1"
CDS_SEC"1";
"B"
$PN"2"3;
"A"
$PN"1"8;
%"Q_RES"
"1","(1925,-475)","0","pure_quanta","I201";
;
PART_NUMBER"CS31002FB08"
TOLERANCE"1%"
VALUE"10K"
MATERIAL"CHIP"
$LOCATION"R4115"
WATTAGE"1/16W"
PACK_TYPE"0402LF"
CDS_LIB"pure_quanta"
CDS_LOCATION"R4115"
$SEC"1"
CDS_SEC"1";
"B"
$PN"2"3;
"A"
$PN"1"50;
%"Q_RES"
"1","(1925,25)","0","pure_quanta","I202";
;
PART_NUMBER"CS31002FB08"
MATERIAL"CHIP"
TOLERANCE"1%"
VALUE"10K"
$LOCATION"R4110"
WATTAGE"1/16W"
PACK_TYPE"0402LF"
CDS_LIB"pure_quanta"
CDS_LOCATION"R4110"
$SEC"1"
CDS_SEC"1";
"B"
$PN"2"3;
"A"
$PN"1"46;
%"Q_RES"
"1","(1925,-175)","0","pure_quanta","I203";
;
PART_NUMBER"CS31002FB08"
VALUE"10K"
MATERIAL"CHIP"
TOLERANCE"1%"
$LOCATION"R4112"
WATTAGE"1/16W"
PACK_TYPE"0402LF"
CDS_LIB"pure_quanta"
CDS_LOCATION"R4112"
$SEC"1"
CDS_SEC"1";
"B"
$PN"2"3;
"A"
$PN"1"36;
%"Q_RES"
"1","(1925,-75)","0","pure_quanta","I204";
;
PART_NUMBER"CS31002FB08"
VALUE"10K"
TOLERANCE"1%"
MATERIAL"CHIP"
$LOCATION"R4111"
WATTAGE"1/16W"
PACK_TYPE"0402LF"
CDS_LIB"pure_quanta"
CDS_LOCATION"R4111"
$SEC"1"
CDS_SEC"1";
"B"
$PN"2"3;
"A"
$PN"1"48;
%"Q_RES"
"1","(1925,-375)","0","pure_quanta","I205";
;
PART_NUMBER"CS31002FB08"
TOLERANCE"1%"
VALUE"10K"
MATERIAL"CHIP"
$LOCATION"R4114"
WATTAGE"1/16W"
PACK_TYPE"0402LF"
CDS_LIB"pure_quanta"
CDS_LOCATION"R4114"
$SEC"1"
CDS_SEC"1";
"B"
$PN"2"3;
"A"
$PN"1"35;
%"Q_RES"
"1","(1925,-275)","0","pure_quanta","I206";
;
PART_NUMBER"CS31002FB08"
TOLERANCE"1%"
VALUE"10K"
MATERIAL"CHIP"
$LOCATION"R4113"
WATTAGE"1/16W"
PACK_TYPE"0402LF"
CDS_LIB"pure_quanta"
CDS_LOCATION"R4113"
$SEC"1"
CDS_SEC"1";
"B"
$PN"2"3;
"A"
$PN"1"43;
%"Q_RES"
"1","(1925,-575)","0","pure_quanta","I207";
;
PART_NUMBER"CS31002FB08"
VALUE"10K"
TOLERANCE"1%"
MATERIAL"CHIP"
$LOCATION"R4116"
CDS_LIB"pure_quanta"
PACK_TYPE"0402LF"
WATTAGE"1/16W"
CDS_LOCATION"R4116"
$SEC"1"
CDS_SEC"1";
"B"
$PN"2"3;
"A"
$PN"1"49;
%"UNIVERSAL_GND"
"1","(2450,-1075)","0","logical_power","I208";
;
CDS_LIB"logical_power"
HDL_POWER"GND";
"A"3;
%"Q_RES"
"1","(1925,-675)","0","pure_quanta","I209";
;
PART_NUMBER"CS31002FB08"
VALUE"10K"
TOLERANCE"1%"
MATERIAL"CHIP"
$LOCATION"R4117"
PACK_TYPE"0402LF"
WATTAGE"1/16W"
CDS_LIB"pure_quanta"
CDS_LOCATION"R4117"
$SEC"1"
CDS_SEC"1";
"B"
$PN"2"3;
"A"
$PN"1"52;
%"EMMITSBURG_REV0P9"
"6","(1600,2400)","0","pure_quanta","I22";
;
PART_NUMBER"AJ0QV2N0T00"
VALUE"GFNOCPU04302300-QV2N-MM#99A1WT"
PART_TYPE"SMLF"
MATERIAL"IC"
$LOCATION"U4"
CDS_LIB"pure_quanta"
CDS_LMAN_SYM_OUTLINE"-1825,975,1825,-975"
NEEDS_NO_SIZE"TRUE"
CDS_LOCATION"U4"
$SEC"6"
CDS_SEC"6";
"GPP_M_8"
$PN"W10"18;
"GPP_M_7"
$PN"AB11"38;
"GPP_M_6"
$PN"R10"17;
"GPP_M_5"
$PN"V8"16;
"GPP_M_4"
$PN"W7"15;
"GPP_M_3"
$PN"AA10"37;
"GPP_M_2"
$PN"AA7"14;
"GPP_M_17"
$PN"W13"57;
"GPP_M_16"
$PN"N10"56;
"GPP_M_15"
$PN"T8"55;
"GPP_M_12"
$PN"U7"20;
"GPP_M_11"
$PN"R7"19;
"GPP_M_1"
$PN"AA13"13;
"GPP_M_0"
$PN"N7"12;
"GPP_L_8"
$PN"AE10"29;
"GPP_L_7"
$PN"AC7"30;
"GPP_L_6"
$PN"AG10"34;
"GPP_L_5"
$PN"AB8"33;
"GPP_L_4"
$PN"AG7"39;
"GPP_L_3"
$PN"AF11"40;
"GPP_L_2"
$PN"AC10"32;
"GPP_L_1_PM_DOWN_0"
$PN"AE7"41;
"GPP_L_0_PM_SYNC_0"
$PN"AF8"31;
"GPP_I_23"
$PN"R4"42;
"GPP_I_22"
$PN"P3"28;
"GPP_I_21"
$PN"N4"27;
"GPP_I_17_HDA_SDI_1"
$PN"V4"26;
"GPP_I_16_HDA_SDI_0"
$PN"U1"25;
"GPP_I_15_HDA_SDO"
$PN"R2"24;
"GPP_I_14_HDA_SYNC"
$PN"P1"23;
"GPP_I_13_HDA_RST_N \B"
$PN"N2"22;
"GPP_I_12_HDA_BCLK"
$PN"U3"21;
"GPP_E_9_SATA0_SLOAD_SATA0_DEVSLP"
$PN"BA29"68;
"GPP_E_8_SATA0_SCLOCK_SATA0_LED_N \B"
$PN"AW36"69;
"GPP_E_7_SATA0_USB3_XPCIE_1"
$PN"AW32"70;
"GPP_E_6_SATA0_USB3_XPCIE_0"
$PN"BB24"80;
"GPP_E_5_SATA0_XPCIE_3"
$PN"AV28"76;
"GPP_E_4_SATA0_XPCIE_2"
$PN"AV24"75;
"GPP_E_3_SATA1_XPCIE_3"
$PN"BB21"74;
"GPP_E_2_SATA1_XPCIE_2"
$PN"AW23"73;
"GPP_E_1_SATA1_XPCIE_1"
$PN"BA23"60;
"GPP_E_19_ERR2_N \B"
$PN"BB31"83;
"GPP_E_18_ERR1_N \B"
$PN"BA20"86;
"GPP_E_17_ERR0_N \B"
$PN"BA36"82;
"GPP_E_16_SATA2_SDATAOUT_SATA2_DEVSLP"
$PN"AW29"81;
"GPP_E_15_SATA2_SLOAD_SATA2_GP"
$PN"AW20"72;
"GPP_E_14_SATA2_SCLOCK_SATA2_LED_N \B"
$PN"BB34"64;
"GPP_E_13_SATA1_SDATAOUT_SATA1_DEVSLP"
$PN"BA32"71;
"GPP_E_12_SATA1_SLOAD_SATA1_GP"
$PN"BB28"65;
"GPP_E_11_SATA1_SCLOCK_SATA1_LED_N \B"
$PN"AV34"66;
"GPP_E_10_SATA0_SDATAOUT_SATA0_GP"
$PN"AV31"67;
"GPP_E_0_SATA1_XPCIE_0"
$PN"BA26"61;
"GPPC_H_7"
$PN"K3"85;
"GPPC_H_6"
$PN"L2"54;
"GPPC_H_19"
$PN"L4"62;
"GPPC_H_18_PMCALERT_N \B"
$PN"J4"79;
"GPPC_H_17_FLEX_CLK_OUT_2"
$PN"H3"63;
"GPPC_H_16_FLEX_CLK_OUT_1"
$PN"G2"84;
"GPPC_H_15_FLEX_CLK_OUT_0"
$PN"J2"78;
"GPPC_H_1"
$PN"K1"58;
"GPPC_H_0"
$PN"G4"59;
%"Q_RES"
"1","(1925,-775)","0","pure_quanta","I239";
;
PART_NUMBER"CS31002FB08"
VALUE"10K"
MATERIAL"CHIP"
TOLERANCE"1%"
$LOCATION"R4564"
WATTAGE"1/16W"
PACK_TYPE"0402LF"
CDS_LIB"pure_quanta"
CDS_LOCATION"R4564"
$SEC"1"
CDS_SEC"1";
"B"
$PN"2"3;
"A"
$PN"1"51;
%"Q_RES"
"1","(1925,-875)","0","pure_quanta","I240";
;
PART_NUMBER"CS31002FB08"
MATERIAL"CHIP"
TOLERANCE"1%"
VALUE"10K"
$LOCATION"R4565"
PACK_TYPE"0402LF"
WATTAGE"1/16W"
CDS_LIB"pure_quanta"
CDS_LOCATION"R4565"
$SEC"1"
CDS_SEC"1";
"B"
$PN"2"3;
"A"
$PN"1"7;
%"Q_RES"
"1","(4675,500)","0","pure_quanta","I246";
;
PART_NUMBER"CS31002FB08"
VALUE"10K"
TOLERANCE"1%"
MATERIAL"CHIP"
$LOCATION"R4722"
PACK_TYPE"0402LF"
WATTAGE"1/16W"
CDS_LIB"pure_quanta"
CDS_LOCATION"R4722"
$SEC"1"
CDS_SEC"1";
"B"
$PN"2"1;
"A"
$PN"1"6;
%"UNIVERSAL_POWER"
"1","(5225,850)","0","logical_power","I247";
;
HDL_POWER"P3V3_AUX"
CDS_LIB"logical_power";
"A"1;
END.
